# BASEBOARD_FAB2 (Tioga Pass) — schematic netlist excerpt (pin names and nets, part order shuffled) for the footprints in the layout excerpt that follows; sources: Cadence DE-HDL packaged netlist, KiCad conversion of Wiwynn_Tioga_Pass_MB.brd

R4G12  RES  22.1 1.0% CHIP  pkg 0402  page 233 : A = PWRGD_PVPP_GHJ_R ; B = PWRGD_PVPP_GHJ
C7G17  CAP  0.22UF 16V 10% X7R  pkg 0402  page 105 : A = P3E_CPU0_PE2_SS_TXP<9> ; B = P3E_CPU0_PE2_SS_C_TXP<9>
RF22  RES  1.0K 0.1% CHIP  pkg 0402  page 226 : A = VR_PVDDQ_KLM_AIREF2 ; B = ISENSE_PVDDQ_KLM_PH2_IMON

(kicad_pcb
	(version 20260206)
	(generator "pcbnew")
	(generator_version "10.0")
	(general
		(thickness 1.6)
		(legacy_teardrops no)
	)
	(paper "A4")
	(title_block
		(title "Wiwynn_Tioga_Pass_MB.brd")
		(comment 1 "Tioga Pass / footprints 1046-1048 of 4770")
	)
	(layers
		(0 "F.Cu" signal "TOP")
		(4 "In1.Cu" signal "L2GND")
		(6 "In2.Cu" signal "L3")
		(8 "In3.Cu" signal "L4GND")
		(10 "In4.Cu" signal "L5")
		(12 "In5.Cu" signal "L6GND")
		(14 "In6.Cu" signal "L7VCC")
		(16 "In7.Cu" signal "L8VCC")
		(18 "In8.Cu" signal "L9GND")
		(20 "In9.Cu" signal "L10")
		(22 "In10.Cu" signal "L11GND")
		(24 "In11.Cu" signal "L12")
		(26 "In12.Cu" signal "L13GND")
		(2 "B.Cu" signal "BOTTOM")
		(9 "F.Adhes" user "F.Adhesive")
		(11 "B.Adhes" user "B.Adhesive")
		(13 "F.Paste" user "Package Geometry/Pastemask Top")
		(15 "B.Paste" user "Package Geometry/Pastemask Bottom")
		(5 "F.SilkS" user "Ref Des/Silkscreen Top")
		(7 "B.SilkS" user "Ref Des/Silkscreen Bottom")
		(1 "F.Mask" user "Board Geometry/Soldermask Top")
		(3 "B.Mask" user "Board Geometry/Soldermask Bottom")
		(17 "Dwgs.User" user "User.Drawings")
		(19 "Cmts.User" user "User.Comments")
		(21 "Eco1.User" user "User.Eco1")
		(23 "Eco2.User" user "User.Eco2")
		(25 "Edge.Cuts" user "Board Geometry/Outline")
		(27 "Margin" user)
		(31 "F.CrtYd" user "Package Geometry/Place Bound Top")
		(29 "B.CrtYd" user "Package Geometry/Place Bound Bottom")
		(35 "F.Fab" user "Ref Des/Assembly Top")
		(33 "B.Fab" user "Ref Des/Assembly Bottom")
	)
	(footprint ""
		(layer "F.Cu")
		(at 0.724662 -124.076968 90)
		(property "Reference" "RF22"
			(at -0.8382 -0.67818 90)
			(unlocked yes)
			(layer "F.SilkS")
			(effects
				(font
					(size 0.4064 0.254)
					(thickness 0.1524)
				)
				(justify left)
			)
		)
		(property "Value" ""
			(at 0 0 90)
			(layer "F.Fab")
			(effects
				(font
					(size 1.27 1.27)
				)
			)
		)
		(duplicate_pad_numbers_are_jumpers no)
		(fp_poly
			(pts
				(xy -0.2794 -0.1016) (xy 0.2794 -0.1016) (xy 0.2794 0.9906) (xy -0.2794 0.9906)
			)
			(stroke
				(width 0)
				(type default)
			)
			(fill no)
			(layer "F.CrtYd")
		)
		(fp_line
			(start 0.2794 -0.1016)
			(end -0.2794 -0.1016)
			(stroke
				(width 0.1)
				(type default)
			)
			(layer "F.Fab")
		)
		(fp_line
			(start -0.2794 -0.1016)
			(end -0.2794 0.9906)
			(stroke
				(width 0.1)
				(type default)
			)
			(layer "F.Fab")
		)
		(fp_line
			(start 0.2794 0.9906)
			(end 0.2794 -0.1016)
			(stroke
				(width 0.1)
				(type default)
			)
			(layer "F.Fab")
		)
		(fp_line
			(start -0.2794 0.9906)
			(end 0.2794 0.9906)
			(stroke
				(width 0.1)
				(type default)
			)
			(layer "F.Fab")
		)
		(pad "1" smd rect
			(at 0 0 90)
			(size 0.508 0.508)
			(layers "F.Cu" "F.Mask" "F.Paste")
			(net "VR_PVDDQ_KLM_AIREF2")
		)
		(pad "2" smd rect
			(at 0 0.889 90)
			(size 0.508 0.508)
			(layers "F.Cu" "F.Mask" "F.Paste")
			(net "ISENSE_PVDDQ_KLM_PH2_IMON")
		)
		(zone
			(layer "F.Cu")
			(hatch none 0.5)
			(connect_pads
				(clearance 0)
			)
			(min_thickness 0.25)
			(keepout
				(tracks allowed)
				(vias not_allowed)
				(pads allowed)
				(copperpour not_allowed)
				(footprints allowed)
			)
			(placement
				(enabled no)
				(sheetname "")
			)
			(fill
				(thermal_gap 0.5)
				(thermal_bridge_width 0.5)
				(island_removal_mode 0)
			)
			(polygon
				(pts
					(xy 0.978662 -123.822968) (xy 0.978662 -124.330968) (xy 1.359662 -124.330968) (xy 1.359662 -123.822968)
				)
			)
		)
		(zone
			(layer "F.Cu")
			(hatch none 0.5)
			(connect_pads
				(clearance 0)
			)
			(min_thickness 0.25)
			(keepout
				(tracks not_allowed)
				(vias allowed)
				(pads allowed)
				(copperpour not_allowed)
				(footprints allowed)
			)
			(placement
				(enabled no)
				(sheetname "")
			)
			(fill
				(thermal_gap 0.5)
				(thermal_bridge_width 0.5)
				(island_removal_mode 0)
			)
			(polygon
				(pts
					(xy 1.359662 -123.822968) (xy 1.359662 -124.330968) (xy 0.978662 -124.330968) (xy 0.978662 -123.822968)
				)
			)
		)
	)
	(footprint ""
		(layer "F.Cu")
		(at 376.678444 -10.916158)
		(property "Reference" "C7G17"
			(at 0 0 0)
			(layer "F.SilkS")
			(hide yes)
			(effects
				(font
					(size 1.27 1.27)
				)
			)
		)
		(property "Value" ""
			(at 0 0 0)
			(layer "F.Fab")
			(effects
				(font
					(size 1.27 1.27)
				)
			)
		)
		(duplicate_pad_numbers_are_jumpers no)
		(fp_rect
			(start -0.3048 0.9906)
			(end 0.3048 -0.1016)
			(stroke
				(width 0)
				(type default)
			)
			(fill no)
			(layer "F.CrtYd")
		)
		(fp_line
			(start -0.3048 -0.1016)
			(end -0.3048 0.9906)
			(stroke
				(width 0.1)
				(type default)
			)
			(layer "F.Fab")
		)
		(fp_line
			(start -0.3048 0.9906)
			(end 0.3048 0.9906)
			(stroke
				(width 0.1)
				(type default)
			)
			(layer "F.Fab")
		)
		(fp_line
			(start 0.3048 -0.1016)
			(end -0.3048 -0.1016)
			(stroke
				(width 0.1)
				(type default)
			)
			(layer "F.Fab")
		)
		(fp_line
			(start 0.3048 0.9906)
			(end 0.3048 -0.1016)
			(stroke
				(width 0.1)
				(type default)
			)
			(layer "F.Fab")
		)
		(pad "1" smd rect
			(at 0 0)
			(size 0.508 0.508)
			(layers "F.Cu" "F.Mask" "F.Paste")
			(net "P3E_CPU0_PE2_SS_TXP<9>")
		)
		(pad "2" smd rect
			(at 0 0.889)
			(size 0.508 0.508)
			(layers "F.Cu" "F.Mask" "F.Paste")
			(net "P3E_CPU0_PE2_SS_C_TXP<9>")
		)
		(zone
			(layer "F.Cu")
			(hatch none 0.5)
			(connect_pads
				(clearance 0)
			)
			(min_thickness 0.25)
			(keepout
				(tracks not_allowed)
				(vias allowed)
				(pads allowed)
				(copperpour not_allowed)
				(footprints allowed)
			)
			(placement
				(enabled no)
				(sheetname "")
			)
			(fill
				(thermal_gap 0.5)
				(thermal_bridge_width 0.5)
				(island_removal_mode 0)
			)
			(polygon
				(pts
					(xy 376.424444 -10.281158) (xy 376.932444 -10.281158) (xy 376.932444 -10.662158) (xy 376.424444 -10.662158)
				)
			)
		)
		(zone
			(layer "F.Cu")
			(hatch none 0.5)
			(connect_pads
				(clearance 0)
			)
			(min_thickness 0.25)
			(keepout
				(tracks allowed)
				(vias not_allowed)
				(pads allowed)
				(copperpour not_allowed)
				(footprints allowed)
			)
			(placement
				(enabled no)
				(sheetname "")
			)
			(fill
				(thermal_gap 0.5)
				(thermal_bridge_width 0.5)
				(island_removal_mode 0)
			)
			(polygon
				(pts
					(xy 376.424444 -10.281158) (xy 376.932444 -10.281158) (xy 376.932444 -10.662158) (xy 376.424444 -10.662158)
				)
			)
		)
	)
	(footprint ""
		(layer "F.Cu")
		(at 180.848 -8.255)
		(property "Reference" "R4G12"
			(at 0 0 0)
			(layer "F.SilkS")
			(hide yes)
			(effects
				(font
					(size 1.27 1.27)
				)
			)
		)
		(property "Value" ""
			(at 0 0 0)
			(layer "F.Fab")
			(effects
				(font
					(size 1.27 1.27)
				)
			)
		)
		(duplicate_pad_numbers_are_jumpers no)
		(fp_poly
			(pts
				(xy -0.2794 -0.1016) (xy 0.2794 -0.1016) (xy 0.2794 0.9906) (xy -0.2794 0.9906)
			)
			(stroke
				(width 0)
				(type default)
			)
			(fill no)
			(layer "F.CrtYd")
		)
		(fp_line
			(start -0.2794 -0.1016)
			(end -0.2794 0.9906)
			(stroke
				(width 0.1)
				(type default)
			)
			(layer "F.Fab")
		)
		(fp_line
			(start -0.2794 0.9906)
			(end 0.2794 0.9906)
			(stroke
				(width 0.1)
				(type default)
			)
			(layer "F.Fab")
		)
		(fp_line
			(start 0.2794 -0.1016)
			(end -0.2794 -0.1016)
			(stroke
				(width 0.1)
				(type default)
			)
			(layer "F.Fab")
		)
		(fp_line
			(start 0.2794 0.9906)
			(end 0.2794 -0.1016)
			(stroke
				(width 0.1)
				(type default)
			)
			(layer "F.Fab")
		)
		(pad "1" smd rect
			(at 0 0)
			(size 0.508 0.508)
			(layers "F.Cu" "F.Mask" "F.Paste")
			(net "PWRGD_PVPP_GHJ_R")
		)
		(pad "2" smd rect
			(at 0 0.889)
			(size 0.508 0.508)
			(layers "F.Cu" "F.Mask" "F.Paste")
			(net "PWRGD_PVPP_GHJ")
		)
		(zone
			(layer "F.Cu")
			(hatch none 0.5)
			(connect_pads
				(clearance 0)
			)
			(min_thickness 0.25)
			(keepout
				(tracks allowed)
				(vias not_allowed)
				(pads allowed)
				(copperpour not_allowed)
				(footprints allowed)
			)
			(placement
				(enabled no)
				(sheetname "")
			)
			(fill
				(thermal_gap 0.5)
				(thermal_bridge_width 0.5)
				(island_removal_mode 0)
			)
			(polygon
				(pts
					(xy 180.594 -8.001) (xy 181.102 -8.001) (xy 181.102 -7.62) (xy 180.594 -7.62)
				)
			)
		)
		(zone
			(layer "F.Cu")
			(hatch none 0.5)
			(connect_pads
				(clearance 0)
			)
			(min_thickness 0.25)
			(keepout
				(tracks not_allowed)
				(vias allowed)
				(pads allowed)
				(copperpour not_allowed)
				(footprints allowed)
			)
			(placement
				(enabled no)
				(sheetname "")
			)
			(fill
				(thermal_gap 0.5)
				(thermal_bridge_width 0.5)
				(island_removal_mode 0)
			)
			(polygon
				(pts
					(xy 180.594 -7.62) (xy 181.102 -7.62) (xy 181.102 -8.001) (xy 180.594 -8.001)
				)
			)
		)
	)
)
